(kicad_pcb
	(version 20221018)
	(generator pcbnew)
	(general
    (thickness 1.518)
  )
	(paper "A4")
	(title_block
    (title "Kria K26 Devboard")
    (date "2024-03-26")
    (rev "1.2.5")
    (comment 1 "www.antmicro.com")
    (comment 2 "Antmicro Ltd.")
		(comment 9 "footprints 11-14 of 660")
	)
	(layers
    (0 "F.Cu" mixed)
    (1 "In1.Cu" power)
    (2 "In2.Cu" mixed)
    (3 "In3.Cu" power)
    (4 "In4.Cu" mixed)
    (5 "In5.Cu" power)
    (6 "In6.Cu" mixed)
    (31 "B.Cu" power)
    (32 "B.Adhes" user "B.Adhesive")
    (33 "F.Adhes" user "F.Adhesive")
    (34 "B.Paste" user)
    (35 "F.Paste" user)
    (36 "B.SilkS" user "B.Silkscreen")
    (37 "F.SilkS" user "F.Silkscreen")
    (38 "B.Mask" user)
    (39 "F.Mask" user)
    (40 "Dwgs.User" user "User.Drawings")
    (41 "Cmts.User" user "User.Comments")
    (42 "Eco1.User" user "User.Eco1")
    (43 "Eco2.User" user "User.Eco2")
    (44 "Edge.Cuts" user)
    (45 "Margin" user)
    (46 "B.CrtYd" user "B.Courtyard")
    (47 "F.CrtYd" user "F.Courtyard")
    (48 "B.Fab" user)
    (49 "F.Fab" user)
  )
	(footprint "kria-k26-devboard-footprints:C_0402_1005Metric" (layer "F.Cu")
    (at 163.9 141.878033 90)
    (descr "Capacitor SMD 0402")
    (tags "capacitor SMD 0402")
    (property "Author" "Antmicro")
    (property "Dielectric" "X5R")
    (property "License" "Apache-2.0")
    (property "MPN" "GRM155R61H104KE14D")
    (property "Manufacturer" "Murata")
    (property "Sheetfile" "pmod.kicad_sch")
    (property "Sheetname" "PMOD")
    (property "Val" "100n")
    (property "Voltage" "50V")
    (property "ki_description" " ")
    (attr smd)
    (fp_text reference "C37" (at -1.331967 4.522678 90) (layer "F.SilkS")
        (effects (font (size 0.7 0.7) (thickness 0.15)) (justify left bottom))
    )
    (fp_text value "C_100n_0402" (at 0 1.4 90) (layer "F.Fab") hide
        (effects (font (size 0.7 0.7) (thickness 0.15)) (justify left bottom))
    )
    (fp_text user "License: Apache-2.0" (at -0.932 5.17 90) (layer "F.Fab") hide
        (effects (font (size 0.7 0.7) (thickness 0.15)) (justify left bottom))
    )
    (fp_text user "Author: Antmicro" (at -0.932 4.17 90) (layer "F.Fab") hide
        (effects (font (size 0.7 0.7) (thickness 0.15)) (justify left bottom))
    )
    (fp_text user "${REFERENCE}" (at -0.932 3.168 90) (layer "F.Fab") hide
        (effects (font (size 0.7 0.7) (thickness 0.15)) (justify left bottom))
    )
    (fp_rect (start -0.94 -0.47) (end 0.94 0.47)
      (stroke (width 0.05) (type solid)) (fill none) (layer "F.CrtYd"))
    (fp_rect (start -0.499 -0.249) (end 0.499 0.249)
      (stroke (width 0.15) (type solid)) (fill none) (layer "F.Fab"))
    (pad "1" smd roundrect (at -0.484 0 90) (size 0.59 0.64) (layers "F.Cu" "F.Paste" "F.Mask") (roundrect_rratio 0.25)
      (net 20 "PL_3V3") (pintype "passive"))
    (pad "2" smd roundrect (at 0.484 0 90) (size 0.59 0.64) (layers "F.Cu" "F.Paste" "F.Mask") (roundrect_rratio 0.25)
      (net 1 "GND") (pintype "passive"))
  )
	(footprint "kria-k26-devboard-footprints:C_0402_1005Metric" (layer "F.Cu")
    (at 164.9 141.878033 90)
    (descr "Capacitor SMD 0402")
    (tags "capacitor SMD 0402")
    (property "Author" "Antmicro")
    (property "Dielectric" "X5R")
    (property "License" "Apache-2.0")
    (property "MPN" "GRM155R61H104KE14D")
    (property "Manufacturer" "Murata")
    (property "Sheetfile" "pmod.kicad_sch")
    (property "Sheetname" "PMOD")
    (property "Val" "100n")
    (property "Voltage" "50V")
    (property "ki_description" " ")
    (attr smd)
    (fp_text reference "C38" (at -1.331967 4.522678 90) (layer "F.SilkS")
        (effects (font (size 0.7 0.7) (thickness 0.15)) (justify left bottom))
    )
    (fp_text value "C_100n_0402" (at 0 1.4 90) (layer "F.Fab") hide
        (effects (font (size 0.7 0.7) (thickness 0.15)) (justify left bottom))
    )
    (fp_text user "Author: Antmicro" (at -0.932 4.17 90) (layer "F.Fab") hide
        (effects (font (size 0.7 0.7) (thickness 0.15)) (justify left bottom))
    )
    (fp_text user "${REFERENCE}" (at -0.932 3.168 90) (layer "F.Fab") hide
        (effects (font (size 0.7 0.7) (thickness 0.15)) (justify left bottom))
    )
    (fp_text user "License: Apache-2.0" (at -0.932 5.17 90) (layer "F.Fab") hide
        (effects (font (size 0.7 0.7) (thickness 0.15)) (justify left bottom))
    )
    (fp_rect (start -0.94 -0.47) (end 0.94 0.47)
      (stroke (width 0.05) (type solid)) (fill none) (layer "F.CrtYd"))
    (fp_rect (start -0.499 -0.249) (end 0.499 0.249)
      (stroke (width 0.15) (type solid)) (fill none) (layer "F.Fab"))
    (pad "1" smd roundrect (at -0.484 0 90) (size 0.59 0.64) (layers "F.Cu" "F.Paste" "F.Mask") (roundrect_rratio 0.25)
      (net 20 "PL_3V3") (pintype "passive"))
    (pad "2" smd roundrect (at 0.484 0 90) (size 0.59 0.64) (layers "F.Cu" "F.Paste" "F.Mask") (roundrect_rratio 0.25)
      (net 1 "GND") (pintype "passive"))
  )
	(footprint "kria-k26-devboard-footprints:DisplayPort_Receptacle_Molex_472720001" (layer "F.Cu")
    (at 90.26 59.26 180)
    (property "Author" "Antmicro")
    (property "License" "Apache-2.0")
    (property "MPN" "472720001")
    (property "Manufacturer" "Molex")
    (property "Sheetfile" "dp.kicad_sch")
    (property "Sheetname" "Display Port")
    (property "ki_description" "DisplayPort Receptacle Connector 20 Position Surface Mount, Right Angle; Through Hole")
    (property "ki_keywords" "DISPLAYPORT, CONNECTOR, SMT, THT, HORIZONTAL")
    (attr smd)
    (fp_text reference "J1" (at -14 -0.2 180) (layer "F.SilkS")
        (effects (font (size 0.7 0.7) (thickness 0.15)) (justify left bottom))
    )
    (fp_text value "DisplayPort_Molex_472720001" (at -14.4 16.2 180) (layer "F.Fab") hide
        (effects (font (size 0.7 0.7) (thickness 0.15)) (justify left bottom))
    )
    (fp_text user "${REFERENCE}" (at -14.4 17.601 180) (layer "F.Fab") hide
        (effects (font (size 0.7 0.7) (thickness 0.15)) (justify left bottom))
    )
    (fp_text user "License: Apache-2.0" (at -14.4 20.399 180) (layer "F.Fab") hide
        (effects (font (size 0.7 0.7) (thickness 0.15)) (justify left bottom))
    )
    (fp_text user "Author: Antmicro" (at -14.4 19 180) (layer "F.Fab") hide
        (effects (font (size 0.7 0.7) (thickness 0.15)) (justify left bottom))
    )
    (fp_line (start -8.449 -6.181) (end -8.449 -5.481)
      (stroke (width 0.15) (type solid)) (layer "F.SilkS"))
    (fp_line (start -8.449 -2.05) (end -8.449 1.498)
      (stroke (width 0.15) (type solid)) (layer "F.SilkS"))
    (fp_line (start -8.449 4.53) (end -8.449 6.93)
      (stroke (width 0.15) (type solid)) (layer "F.SilkS"))
    (fp_line (start -4.449 -6.181) (end -8.449 -6.181)
      (stroke (width 0.15) (type solid)) (layer "F.SilkS"))
    (fp_line (start 5.802 -7.37) (end 5.802 -6.181)
      (stroke (width 0.15) (type solid)) (layer "F.SilkS"))
    (fp_line (start 8.45 -6.181) (end 5.802 -6.181)
      (stroke (width 0.15) (type solid)) (layer "F.SilkS"))
    (fp_line (start 8.45 -6.181) (end 8.45 -5.481)
      (stroke (width 0.15) (type solid)) (layer "F.SilkS"))
    (fp_line (start 8.45 -2.05) (end 8.45 1.498)
      (stroke (width 0.15) (type solid)) (layer "F.SilkS"))
    (fp_line (start 8.45 4.53) (end 8.45 6.93)
      (stroke (width 0.15) (type solid)) (layer "F.SilkS"))
    (fp_line (start -9.1 7.6) (end -9.1 8.4)
      (stroke (width 0.05) (type solid)) (layer "F.CrtYd"))
    (fp_line (start -9.1 8.4) (end 9.1 8.4)
      (stroke (width 0.05) (type solid)) (layer "F.CrtYd"))
    (fp_line (start -8.65 -6.37) (end -8.65 7.6)
      (stroke (width 0.05) (type solid)) (layer "F.CrtYd"))
    (fp_line (start -8.65 7.6) (end -9.1 7.6)
      (stroke (width 0.05) (type solid)) (layer "F.CrtYd"))
    (fp_line (start -4.35 -7.77) (end -4.35 -6.37)
      (stroke (width 0.05) (type solid)) (layer "F.CrtYd"))
    (fp_line (start -4.35 -6.37) (end -8.65 -6.37)
      (stroke (width 0.05) (type solid)) (layer "F.CrtYd"))
    (fp_line (start 5.85 -7.77) (end -4.35 -7.77)
      (stroke (width 0.05) (type solid)) (layer "F.CrtYd"))
    (fp_line (start 5.85 -6.37) (end 5.85 -7.77)
      (stroke (width 0.05) (type solid)) (layer "F.CrtYd"))
    (fp_line (start 8.65 -6.37) (end 5.85 -6.37)
      (stroke (width 0.05) (type solid)) (layer "F.CrtYd"))
    (fp_line (start 8.65 7.6) (end 8.65 -6.37)
      (stroke (width 0.05) (type solid)) (layer "F.CrtYd"))
    (fp_line (start 9.1 7.6) (end 8.65 7.6)
      (stroke (width 0.05) (type solid)) (layer "F.CrtYd"))
    (fp_line (start 9.1 8.4) (end 9.1 7.6)
      (stroke (width 0.05) (type solid)) (layer "F.CrtYd"))
    (fp_line (start -8.449 -6.181) (end 8.45 -6.181)
      (stroke (width 0.15) (type solid)) (layer "F.Fab"))
    (fp_line (start -8.449 8.209) (end -8.449 -6.181)
      (stroke (width 0.15) (type solid)) (layer "F.Fab"))
    (fp_line (start 8.45 -6.181) (end 8.45 8.209)
      (stroke (width 0.15) (type solid)) (layer "F.Fab"))
    (fp_line (start 8.45 8.209) (end -8.449 8.209)
      (stroke (width 0.15) (type solid)) (layer "F.Fab"))
    (pad "" np_thru_hole circle (at 0.002 3.909 180) (size 1.4 1.4) (drill 1.4) (layers "*.Cu" "*.Mask"))
    (pad "1" smd rect (at 5.502 -6.37 180) (size 0.28 2.4) (layers "F.Cu" "F.Paste" "F.Mask")
      (net 93 "/Display Port/GTR_DP1_M2C_C_P") (pinfunction "TXD0+") (pintype "bidirectional"))
    (pad "2" smd rect (at 5.002 -6.37 180) (size 0.28 2.4) (layers "F.Cu" "F.Paste" "F.Mask")
      (net 1 "GND") (pinfunction "GND") (pintype "passive"))
    (pad "3" smd rect (at 4.502 -6.37 180) (size 0.28 2.4) (layers "F.Cu" "F.Paste" "F.Mask")
      (net 95 "/Display Port/GTR_DP1_M2C_C_N") (pinfunction "TXD0-") (pintype "bidirectional"))
    (pad "4" smd rect (at 4.002 -6.37 180) (size 0.28 2.4) (layers "F.Cu" "F.Paste" "F.Mask")
      (net 101 "/Display Port/GTR_DP0_M2C_C_P") (pinfunction "TXD1+") (pintype "bidirectional"))
    (pad "5" smd rect (at 3.502 -6.37 180) (size 0.28 2.4) (layers "F.Cu" "F.Paste" "F.Mask")
      (net 1 "GND") (pinfunction "GND") (pintype "passive"))
    (pad "6" smd rect (at 3.002 -6.37 180) (size 0.28 2.4) (layers "F.Cu" "F.Paste" "F.Mask")
      (net 103 "/Display Port/GTR_DP0_M2C_C_N") (pinfunction "TXD1-") (pintype "bidirectional"))
    (pad "7" smd rect (at 2.502 -6.37 180) (size 0.28 2.4) (layers "F.Cu" "F.Paste" "F.Mask")
      (net 344 "unconnected-(J1-TXD2+-Pad7)") (pinfunction "TXD2+") (pintype "bidirectional+no_connect"))
    (pad "8" smd rect (at 2.002 -6.37 180) (size 0.28 2.4) (layers "F.Cu" "F.Paste" "F.Mask")
      (net 1 "GND") (pinfunction "GND") (pintype "passive"))
    (pad "9" smd rect (at 1.502 -6.37 180) (size 0.28 2.4) (layers "F.Cu" "F.Paste" "F.Mask")
      (net 345 "unconnected-(J1-TXD2--Pad9)") (pinfunction "TXD2-") (pintype "bidirectional+no_connect"))
    (pad "10" smd rect (at 1.002 -6.37 180) (size 0.28 2.4) (layers "F.Cu" "F.Paste" "F.Mask")
      (net 346 "unconnected-(J1-TXD3+-Pad10)") (pinfunction "TXD3+") (pintype "bidirectional+no_connect"))
    (pad "11" smd rect (at 0.502 -6.37 180) (size 0.28 2.4) (layers "F.Cu" "F.Paste" "F.Mask")
      (net 1 "GND") (pinfunction "GND") (pintype "power_in"))
    (pad "12" smd rect (at 0.002 -6.37 180) (size 0.28 2.4) (layers "F.Cu" "F.Paste" "F.Mask")
      (net 347 "unconnected-(J1-TXD3--Pad12)") (pinfunction "TXD3-") (pintype "bidirectional+no_connect"))
    (pad "13" smd rect (at -0.498 -6.37 180) (size 0.28 2.4) (layers "F.Cu" "F.Paste" "F.Mask")
      (net 348 "Net-(J1-CFG1)") (pinfunction "CFG1") (pintype "passive"))
    (pad "14" smd rect (at -0.998 -6.37 180) (size 0.28 2.4) (layers "F.Cu" "F.Paste" "F.Mask")
      (net 349 "Net-(J1-CFG2)") (pinfunction "CFG2") (pintype "passive"))
    (pad "15" smd rect (at -1.498 -6.37 180) (size 0.28 2.4) (layers "F.Cu" "F.Paste" "F.Mask")
      (net 362 "/Display Port/DP_AUX_C_TVS_P") (pinfunction "AUX+") (pintype "bidirectional"))
    (pad "16" smd rect (at -1.998 -6.37 180) (size 0.28 2.4) (layers "F.Cu" "F.Paste" "F.Mask")
      (net 1 "GND") (pinfunction "GND") (pintype "passive"))
    (pad "17" smd rect (at -2.498 -6.37 180) (size 0.28 2.4) (layers "F.Cu" "F.Paste" "F.Mask")
      (net 363 "/Display Port/DP_AUX_C_TVS_N") (pinfunction "AUX-") (pintype "bidirectional"))
    (pad "18" smd rect (at -2.998 -6.37 180) (size 0.28 2.4) (layers "F.Cu" "F.Paste" "F.Mask")
      (net 105 "/Display Port/DP_HPD") (pinfunction "HPD") (pintype "passive"))
    (pad "19" smd rect (at -3.498 -6.37 180) (size 0.28 2.4) (layers "F.Cu" "F.Paste" "F.Mask")
      (net 804 "Net-(J1-RTN)") (pinfunction "RTN") (pintype "power_in"))
    (pad "20" smd rect (at -3.998 -6.37 180) (size 0.28 2.4) (layers "F.Cu" "F.Paste" "F.Mask")
      (net 334 "Net-(J1-DP_PWR)") (pinfunction "DP_PWR") (pintype "power_in"))
    (pad "SH" thru_hole oval (at -8.248 -3.771 180) (size 1.4 2.8) (drill oval 0.6 2.2) (layers "*.Cu" "*.Mask")
      (net 319 "SH_UP") (pinfunction "SH") (pintype "passive"))
    (pad "SH" thru_hole oval (at -8.248 3.01 180) (size 1.2 2.4) (drill oval 0.6 1.7) (layers "*.Cu" "*.Mask")
      (net 319 "SH_UP") (pinfunction "SH") (pintype "passive"))
    (pad "SH" thru_hole oval (at 8.251 -3.771 180) (size 1.4 2.8) (drill oval 0.6 2.2) (layers "*.Cu" "*.Mask")
      (net 319 "SH_UP") (pinfunction "SH") (pintype "passive"))
    (pad "SH" thru_hole oval (at 8.251 3.01 180) (size 1.2 2.4) (drill oval 0.6 1.7) (layers "*.Cu" "*.Mask")
      (net 319 "SH_UP") (pinfunction "SH") (pintype "passive"))
  )
	(footprint "kria-k26-devboard-footprints:PinSocket_2x6_P2.54mm_Drill1.04mm_Horizontal" (layer "F.Cu")
    (at 178.078 146.799 180)
    (property "Author" "Antmicro")
    (property "License" "Apache-2.0")
    (property "MPN" "SSW-106-02-G-D-RA")
    (property "Manufacturer" "Samtec")
    (property "Sheetfile" "pmod.kicad_sch")
    (property "Sheetname" "PMOD")
    (property "ki_description" "PCB Receptacle, Board-to-Board, 2.54 mm, 2 Rows, 12 Contacts, Through Hole Mount Right Angle, SSW")
    (property "ki_keywords" "CONNECTOR, SOCKET, THT, HORIZONTAL")
    (attr through_hole)
    (fp_text reference "J4" (at 0 -11.25 180) (layer "F.SilkS")
        (effects (font (size 0.7 0.7) (thickness 0.15)) (justify left bottom))
    )
    (fp_text value "PinSocket_2x6_P2.54mm_Drill1.04mm_Horizontal" (at 0 4.75 180) (layer "F.Fab") hide
        (effects (font (size 0.7 0.7) (thickness 0.15)) (justify left bottom))
    )
    (fp_text user "Author: Antmicro" (at -2.275 8.298 180) (layer "F.Fab") hide
        (effects (font (size 0.7 0.7) (thickness 0.15)) (justify left bottom))
    )
    (fp_text user "${REFERENCE}" (at -2.275 7.099 180) (layer "F.Fab") hide
        (effects (font (size 0.7 0.7) (thickness 0.15)) (justify left bottom))
    )
    (fp_text user "License: Apache-2.0" (at -2.275 9.499 180) (layer "F.Fab") hide
        (effects (font (size 0.7 0.7) (thickness 0.15)) (justify left bottom))
    )
    (fp_line (start -1.526 -1.524) (end -1.526 -10.035)
      (stroke (width 0.15) (type solid)) (layer "F.SilkS"))
    (fp_line (start 14.223 -10.035) (end -1.526 -10.035)
      (stroke (width 0.15) (type solid)) (layer "F.SilkS"))
    (fp_line (start 14.223 -10.035) (end 14.223 -1.524)
      (stroke (width 0.15) (type solid)) (layer "F.SilkS"))
    (fp_line (start 14.223 -1.524) (end -1.526 -1.524)
      (stroke (width 0.15) (type solid)) (layer "F.SilkS"))
    (fp_circle (center -2.2 0) (end -2.15 0)
      (stroke (width 0.15) (type solid)) (fill solid) (layer "F.SilkS"))
    (fp_rect (start -2.524 -11.01) (end 15.223 3.766)
      (stroke (width 0.05) (type solid)) (fill none) (layer "F.CrtYd"))
    (fp_line (start -1.526 -10.035) (end 14.223 -10.035)
      (stroke (width 0.15) (type solid)) (layer "F.Fab"))
    (fp_line (start -1.526 -10.035) (end 14.223 -10.035)
      (stroke (width 0.15) (type solid)) (layer "F.Fab"))
    (fp_line (start -1.526 -1.524) (end -1.526 -10.035)
      (stroke (width 0.15) (type solid)) (layer "F.Fab"))
    (fp_line (start -1.526 -1.524) (end -1.526 -10.035)
      (stroke (width 0.15) (type solid)) (layer "F.Fab"))
    (fp_line (start 14.223 -10.035) (end 14.223 -1.524)
      (stroke (width 0.15) (type solid)) (layer "F.Fab"))
    (fp_line (start 14.223 -10.035) (end 14.223 -1.524)
      (stroke (width 0.15) (type solid)) (layer "F.Fab"))
    (fp_line (start 14.223 -1.524) (end -1.526 -1.524)
      (stroke (width 0.15) (type solid)) (layer "F.Fab"))
    (pad "1" thru_hole rect (at 0 0 180) (size 1.84 1.84) (drill 1.04) (layers "*.Cu" "*.Mask")
      (net 144 "/PMOD/HDA11") (pintype "passive"))
    (pad "2" thru_hole circle (at 0 2.539 180) (size 1.84 1.84) (drill 1.04) (layers "*.Cu" "*.Mask")
      (net 146 "/PMOD/HDA15") (pintype "passive"))
    (pad "3" thru_hole circle (at 2.539 0 180) (size 1.84 1.84) (drill 1.04) (layers "*.Cu" "*.Mask")
      (net 155 "/PMOD/HDA12") (pintype "passive"))
    (pad "4" thru_hole circle (at 2.539 2.539 180) (size 1.8 1.8) (drill 1.04) (layers "*.Cu" "*.Mask")
      (net 147 "/PMOD/HDA16_CC") (pintype "passive"))
    (pad "5" thru_hole circle (at 5.078 0 180) (size 1.84 1.84) (drill 1.04) (layers "*.Cu" "*.Mask")
      (net 156 "/PMOD/HDA13") (pintype "passive"))
    (pad "6" thru_hole circle (at 5.078 2.539 180) (size 1.84 1.84) (drill 1.04) (layers "*.Cu" "*.Mask")
      (net 148 "/PMOD/HDA17") (pintype "passive"))
    (pad "7" thru_hole circle (at 7.618 0 180) (size 1.84 1.84) (drill 1.04) (layers "*.Cu" "*.Mask")
      (net 157 "/PMOD/HDA14") (pintype "passive"))
    (pad "8" thru_hole circle (at 7.618 2.539 180) (size 1.84 1.84) (drill 1.04) (layers "*.Cu" "*.Mask")
      (net 152 "/PMOD/HDA18") (pintype "passive"))
    (pad "9" thru_hole circle (at 10.159 0 180) (size 1.84 1.84) (drill 1.04) (layers "*.Cu" "*.Mask")
      (net 1 "GND") (pintype "passive"))
    (pad "10" thru_hole circle (at 10.159 2.539 180) (size 1.84 1.84) (drill 1.04) (layers "*.Cu" "*.Mask")
      (net 1 "GND") (pintype "passive"))
    (pad "11" thru_hole circle (at 12.698 0 180) (size 1.84 1.84) (drill 1.04) (layers "*.Cu" "*.Mask")
      (net 20 "PL_3V3") (pintype "passive"))
    (pad "12" thru_hole circle (at 12.698 2.539 180) (size 1.84 1.84) (drill 1.04) (layers "*.Cu" "*.Mask")
      (net 20 "PL_3V3") (pintype "passive"))
  )
)
